POWER AND GROUND LIST - 1  
DESIGNATOR       PART TYPE        
U1B2             PCA9517_SM-IC,G77073-001-GND=GA 
                        GND      
                        4        
U1D1             TTL1G126_A_SOT-74HC1G126,IC,A7B 
                        GND      P3V3_STBY 
                        3        5        
U1E2             TTL1G08_SOTLF-NC7SZ08,IC,D1032B 
                        GND      P3V3_STBY 
                        3        5        
U1L1             TTL3126_QFNLF-74CBTLV3126,IC,DB 
                        GND      P3V3_STBY 
                        7        14       
                        15                
U1L2             TTL1G86_SOTLF-74AHCT1G86,IC,D3B 
                        GND      P5V_STBY 
                        3        5        
U1L3             ADM809_SMLF-IC,D23047-001-GND=A 
                        GND      
                        1        
U1L4             TTL1G07_A_SOP-74LVC1G07,IC,C88B 
                        GND      P3V3_STBY 
                        3        5        
U1L5             TTL3126_QFNLF-74CBTLV3126,IC,DB 
                        GND      P3V3_STBY 
                        7        14       
                        15                
U1M1             TTL1G08_SOTLF-NC7SZ08,IC,D1032C 
                        GND      P3V3     
                        3        5        
U1M4             74CBTLV1G125_SMLF-IC,C88177-00A 
                        GND      P3V3_STBY 
                        3        5        
U1M5             74CBTLV1G125_SMLF-IC,C88177-00A 
                        GND      P3V3_STBY 
                        3        5        
U1M6             74CBTLV1G125_SMLF-IC,C88177-00A 
                        GND      P3V3_STBY 
                        3        5        
U1R1             TTL1G07_A_SOP-74LVC1G07,IC,C88B 
                        GND      P3V3_STBY 
                        3        5        
U1R2             TTL1G126_A_SOT-74HC1G126,IC,A7B 
                        GND      P3V3_STBY 
                        3        5        
U2P1             TTL1G07_A_SOP-74LVC1G07,IC,C88B 
                        GND      P3V3_STBY 
                        3        5        
U2R1             TTL2G14_SMLF-74LVC2G14,IC,D184B 
                        GND      P3V3_STBY 
                        2        5        
U2T2             TTL1G32_A_SOT-74LVC1G32,IC,E60B 
                        GND      P3V3_STBY 
                        3        5        
U2T3             TTL1G32_A_SOT-74LVC1G32,IC,E60B 
                        GND      P3V3_STBY 
                        3        5        
U3B1             PCA9617_SSOP-IC,G81764-001-GNDA 
                        GND      
                        4        
U4G1             PCA9617_SSOP-IC,G81764-001-GNDA 
                        GND      
                        4        
U4R1             74CBTLV1G125_SMLF-IC,C88177-00A 
                        GND      P3V3_STBY 
                        3        5        
U6F1             PCA9617_SSOP-IC,G81764-001-GNDA 
                        GND      
                        4        
U6M1             74CBTLV1G125_SMLF-IC,C88177-00A 
                        GND      P3V3_STBY 
                        3        5        
U7D1             74CBTLV1G125_SMLF-IC,C88177-00A 
                        GND      P3V3_STBY 
                        3        5        
U7E1             PCA9617_SSOP-IC,G81764-001-GNDA 
                        GND      
                        4        
U7E2             TTL1G08_SOTLF-NC7SZ08,IC,D1032B 
                        GND      P3V3_STBY 
                        3        5        
U7E3             TTL1G08_SOTLF-NC7SZ08,IC,D1032B 
                        GND      P3V3_STBY 
                        3        5        
U8D2             TTL1G07_A_SOP-74LVC1G07,IC,C88B 
                        GND      P3V3_STBY 
                        3        5        
U8D3             TTL1G07_A_SOP-74LVC1G07,IC,C88B 
                        GND      P3V3_STBY 
                        3        5        
U8D4             AT24C64_SOICLF-IC,C47049-001-GA 
                        GND      P3V3_STBY 
                        4        8        
U8D5             TTL1G126_A_SOT-74HC1G126,IC,A7B 
                        GND      P3V3_STBY 
                        3        5        
U8E1             TTL08_QFN15-74LVC08A,IC,D90404B 
                        GND      P3V3_STBY 
                        7        14       
                        15                
U8E2             ADM809_SMLF-IC,D23047-001-GND=A 
                        GND      
                        1        
U8E3             TTL1G126_A_SOT-74HC1G126,IC,A7B 
                        GND      P3V3_STBY 
                        3        5        
U8E4             TTL1G126_A_SOT-74HC1G126,IC,A7B 
                        GND      P3V3_STBY 
                        3        5        
U8F3             TTL2G07_SOT23LF-74LVC2G07,IC,DB 
                        GND      P3V3_STBY 
                        2        5        
U8G1             TTL2G07_SOT23LF-74LVC2G07,IC,DB 
                        GND      P3V3_STBY 
                        2        5        
U8G2             TTL1G07_A_SOP-74LVC1G07,IC,C88B 
                        GND      P3V3_STBY 
                        3        5        
U8G3             TTL1G07_A_SOP-74LVC1G07,IC,C88B 
                        GND      P3V3_STBY 
                        3        5        
U9A1             TTL1G07_A_SOP-74LVC1G07,IC,C88B 
                        GND      P3V3_STBY 
                        3        5        
U9A3             TTL2G14_SMLF-74LVC2G14,IC,D184B 
                        GND      P3V3_STBY 
                        2        5        
U9A4             TTL2G14_SMLF-74LVC2G14,IC,D184B 
                        GND      P3V3_STBY 
                        2        5        
U9A5             74CBTLV1G125_SMLF-IC,C88177-00A 
                        GND      P3V3_STBY 
                        3        5        
U9F3             TTL1G07_A_SOP-74LVC1G07,IC,C88B 
                        GND      P3V3_STBY 
                        3        5        
Y7C1             CRYSTAL_2013-48.000MHZ,IC,D717A 
                        GND      
                        2        
                        4        
Y8C1             CRYSTAL_2013-25.000MHZ,IC,H196A 
                        GND      
                        2        
                        4        
Y8F1             CRYSTAL_2013LF-25.000MHZ,IC,D7B 
                        GND      
                        2        
                        4        
Y9E1             CRYSTAL_2013-25.000MHZ,IC,D717A 
                        GND      
                        2        
                        4        
END POWER AND GROUND LIST
